# T6G (Grand Teton) — schematic netlist excerpt (pin names and nets, part order shuffled) for the footprints in the layout excerpt that follows; sources: Cadence DE-HDL packaged netlist, KiCad conversion of 04192023_DAF0TMB3IC0_F0TG_MB_C_brd_V02_OCP.brd

PC211_1  Q_CAP  22UF 16V 20% X6S  pkg C0805  page 208 : A = SW_P12V_AUX_PVDD11_S3_P0_FLT ; B = GND
R541  Q_RES  1K 1% EMPTY  pkg 0402LF  page 55 : A = PVDD11_S3_P1 ; B = I3C_1_SPD_DDRGL_CPU1_R_SDA

(kicad_pcb
	(version 20260206)
	(generator "pcbnew")
	(generator_version "10.0")
	(general
		(thickness 1.6)
		(legacy_teardrops no)
	)
	(paper "A4")
	(title_block
		(title "04192023_DAF0TMB3IC0_F0TG_MB_C_brd_V02_OCP.brd")
		(comment 1 "Grand Teton / footprints 7563-7564 of 8354")
	)
	(layers
		(0 "F.Cu" signal "TOP")
		(4 "In1.Cu" signal "GND")
		(6 "In2.Cu" signal "IN1")
		(8 "In3.Cu" signal "GND1")
		(10 "In4.Cu" signal "IN2")
		(12 "In5.Cu" signal "GND2")
		(14 "In6.Cu" signal "IN3")
		(16 "In7.Cu" signal "GND3")
		(18 "In8.Cu" signal "VCC")
		(20 "In9.Cu" signal "VCC1")
		(22 "In10.Cu" signal "GND4")
		(24 "In11.Cu" signal "IN4")
		(26 "In12.Cu" signal "GND5")
		(28 "In13.Cu" signal "IN5")
		(30 "In14.Cu" signal "GND6")
		(32 "In15.Cu" signal "IN6")
		(34 "In16.Cu" signal "GND7")
		(2 "B.Cu" signal "BOTTOM")
		(9 "F.Adhes" user "F.Adhesive")
		(11 "B.Adhes" user "B.Adhesive")
		(13 "F.Paste" user "Package Geometry/Pastemask Top")
		(15 "B.Paste" user "Package Geometry/Pastemask Bottom")
		(5 "F.SilkS" user "Ref Des/Silkscreen Top")
		(7 "B.SilkS" user "Ref Des/Silkscreen Bottom")
		(1 "F.Mask" user "Board Geometry/Soldermask Top")
		(3 "B.Mask" user "Board Geometry/Soldermask Bottom")
		(17 "Dwgs.User" user "User.Drawings")
		(19 "Cmts.User" user "User.Comments")
		(21 "Eco1.User" user "User.Eco1")
		(23 "Eco2.User" user "User.Eco2")
		(25 "Edge.Cuts" user "Board Geometry/Outline")
		(27 "Margin" user)
		(31 "F.CrtYd" user "Package Geometry/Place Bound Top")
		(29 "B.CrtYd" user "Package Geometry/Place Bound Bottom")
		(35 "F.Fab" user "Ref Des/Assembly Top")
		(33 "B.Fab" user "Ref Des/Assembly Bottom")
	)
	(footprint ""
		(layer "B.Cu")
		(at 160.7312 -191.1604 -90)
		(property "Reference" "R541"
			(at 0 0 90)
			(layer "B.SilkS")
			(hide yes)
			(effects
				(font
					(size 1.27 1.27)
				)
				(justify mirror)
			)
		)
		(property "Value" ""
			(at 0 0 90)
			(layer "B.Fab")
			(effects
				(font
					(size 1.27 1.27)
				)
				(justify mirror)
			)
		)
		(duplicate_pad_numbers_are_jumpers no)
		(fp_line
			(start -0.7874 0.4064)
			(end 0.7874 0.4064)
			(stroke
				(width 0.1524)
				(type default)
			)
			(layer "B.SilkS")
		)
		(fp_line
			(start 0.7874 0.4064)
			(end 0.7874 -0.4064)
			(stroke
				(width 0.1524)
				(type default)
			)
			(layer "B.SilkS")
		)
		(fp_line
			(start -0.7874 -0.4064)
			(end -0.7874 0.4064)
			(stroke
				(width 0.1524)
				(type default)
			)
			(layer "B.SilkS")
		)
		(fp_line
			(start 0.7874 -0.4064)
			(end -0.7874 -0.4064)
			(stroke
				(width 0.1524)
				(type default)
			)
			(layer "B.SilkS")
		)
		(fp_line
			(start -0.67945 0.3048)
			(end -0.120396 0.3048)
			(stroke
				(width 0.1)
				(type default)
			)
			(layer "B.Fab")
		)
		(fp_line
			(start -0.120396 0.3048)
			(end -0.120396 0.2794)
			(stroke
				(width 0.1)
				(type default)
			)
			(layer "B.Fab")
		)
		(fp_line
			(start 0.12065 0.3048)
			(end 0.67945 0.3048)
			(stroke
				(width 0.1)
				(type default)
			)
			(layer "B.Fab")
		)
		(fp_line
			(start 0.67945 0.3048)
			(end 0.67945 -0.305054)
			(stroke
				(width 0.1)
				(type default)
			)
			(layer "B.Fab")
		)
		(fp_line
			(start -0.120396 0.2794)
			(end 0.12065 0.2794)
			(stroke
				(width 0.1)
				(type default)
			)
			(layer "B.Fab")
		)
		(fp_line
			(start 0.12065 0.2794)
			(end 0.12065 0.3048)
			(stroke
				(width 0.1)
				(type default)
			)
			(layer "B.Fab")
		)
		(fp_line
			(start -0.12065 -0.2794)
			(end -0.12065 -0.3048)
			(stroke
				(width 0.1)
				(type default)
			)
			(layer "B.Fab")
		)
		(fp_line
			(start 0.12065 -0.2794)
			(end -0.12065 -0.2794)
			(stroke
				(width 0.1)
				(type default)
			)
			(layer "B.Fab")
		)
		(fp_line
			(start -0.67945 -0.3048)
			(end -0.67945 0.3048)
			(stroke
				(width 0.1)
				(type default)
			)
			(layer "B.Fab")
		)
		(fp_line
			(start -0.12065 -0.3048)
			(end -0.67945 -0.3048)
			(stroke
				(width 0.1)
				(type default)
			)
			(layer "B.Fab")
		)
		(fp_line
			(start 0.12065 -0.305054)
			(end 0.12065 -0.2794)
			(stroke
				(width 0.1)
				(type default)
			)
			(layer "B.Fab")
		)
		(fp_line
			(start 0.67945 -0.305054)
			(end 0.12065 -0.305054)
			(stroke
				(width 0.1)
				(type default)
			)
			(layer "B.Fab")
		)
		(pad "1" smd circle
			(at 0.40005 0 90)
			(size 0 0)
			(layers "B.Cu" "B.Mask" "B.Paste")
			(net "PVDD11_S3_P1")
		)
		(pad "2" smd circle
			(at -0.40005 0 90)
			(size 0 0)
			(layers "B.Cu" "B.Mask" "B.Paste")
			(net "I3C_1_SPD_DDRGL_CPU1_R_SDA")
		)
	)
	(footprint ""
		(layer "B.Cu")
		(at 426.702474 -351.032826 90)
		(property "Reference" "PC211_1"
			(at 0 0 90)
			(layer "B.SilkS")
			(hide yes)
			(effects
				(font
					(size 1.27 1.27)
				)
				(justify mirror)
			)
		)
		(property "Value" ""
			(at 0 0 90)
			(layer "B.Fab")
			(effects
				(font
					(size 1.27 1.27)
				)
				(justify mirror)
			)
		)
		(duplicate_pad_numbers_are_jumpers no)
		(fp_line
			(start 1.524 -0.762)
			(end -1.524 -0.762)
			(stroke
				(width 0.1524)
				(type default)
			)
			(layer "B.SilkS")
		)
		(fp_line
			(start -1.524 -0.762)
			(end -1.524 0.762)
			(stroke
				(width 0.1524)
				(type default)
			)
			(layer "B.SilkS")
		)
		(fp_line
			(start 1.524 0.762)
			(end 1.524 -0.762)
			(stroke
				(width 0.1524)
				(type default)
			)
			(layer "B.SilkS")
		)
		(fp_line
			(start -1.524 0.762)
			(end 1.524 0.762)
			(stroke
				(width 0.1524)
				(type default)
			)
			(layer "B.SilkS")
		)
		(fp_line
			(start 1.1049 -0.724916)
			(end 1.1049 0.724916)
			(stroke
				(width 0.1)
				(type default)
			)
			(layer "B.Fab")
		)
		(fp_line
			(start -1.1049 -0.724916)
			(end 1.1049 -0.724916)
			(stroke
				(width 0.1)
				(type default)
			)
			(layer "B.Fab")
		)
		(fp_line
			(start 1.1049 0.724916)
			(end -1.1049 0.724916)
			(stroke
				(width 0.1)
				(type default)
			)
			(layer "B.Fab")
		)
		(fp_line
			(start -1.1049 0.724916)
			(end -1.1049 -0.724916)
			(stroke
				(width 0.1)
				(type default)
			)
			(layer "B.Fab")
		)
		(pad "1" smd rect
			(at 0.889 0 90)
			(size 1.016 1.27)
			(layers "B.Cu" "B.Mask" "B.Paste")
			(net "SW_P12V_AUX_PVDD11_S3_P0_FLT")
		)
		(pad "2" smd rect
			(at -0.889 0 90)
			(size 1.016 1.27)
			(layers "B.Cu" "B.Mask" "B.Paste")
			(net "GND")
		)
	)
)
